# S9S_MB_2U (Grand Teton) — schematic netlist excerpt (pin names and nets, part order shuffled) for the footprints in the layout excerpt that follows; sources: Cadence DE-HDL packaged netlist, KiCad conversion of 03242023_DA0F0TMBIJ0_F0T_Motherboard_J_brd_V01_OCP.brd

R3578  Q_RES  10 1% CHIP  pkg 0402LF  page 172 : A = P12V_SCM_R ; B = VSENSE_P12V_INA230_5_INP
PR4239  Q_RES  0 5% EMPTY  pkg 0402LF  page 284 : A = PVCCFA_EHV_FIVRA_CPU1_IMON3 ; B = GND

(kicad_pcb
	(version 20260206)
	(generator "pcbnew")
	(generator_version "10.0")
	(general
		(thickness 1.6)
		(legacy_teardrops no)
	)
	(paper "A4")
	(title_block
		(title "03242023_DA0F0TMBIJ0_F0T_Motherboard_J_brd_V01_OCP.brd")
		(comment 1 "Grand Teton / footprints 5006-5007 of 6105")
	)
	(layers
		(0 "F.Cu" signal "TOP")
		(4 "In1.Cu" signal "GND")
		(6 "In2.Cu" signal "IN1")
		(8 "In3.Cu" signal "GND1")
		(10 "In4.Cu" signal "IN2")
		(12 "In5.Cu" signal "GND2")
		(14 "In6.Cu" signal "IN3")
		(16 "In7.Cu" signal "GND3")
		(18 "In8.Cu" signal "VCC")
		(20 "In9.Cu" signal "VCC1")
		(22 "In10.Cu" signal "GND4")
		(24 "In11.Cu" signal "IN4")
		(26 "In12.Cu" signal "GND5")
		(28 "In13.Cu" signal "IN5")
		(30 "In14.Cu" signal "GND6")
		(32 "In15.Cu" signal "IN6")
		(34 "In16.Cu" signal "GND7")
		(2 "B.Cu" signal "BOTTOM")
		(9 "F.Adhes" user "F.Adhesive")
		(11 "B.Adhes" user "B.Adhesive")
		(13 "F.Paste" user "Package Geometry/Pastemask Top")
		(15 "B.Paste" user "Package Geometry/Pastemask Bottom")
		(5 "F.SilkS" user "Ref Des/Silkscreen Top")
		(7 "B.SilkS" user "Ref Des/Silkscreen Bottom")
		(1 "F.Mask" user "Board Geometry/Soldermask Top")
		(3 "B.Mask" user "Board Geometry/Soldermask Bottom")
		(17 "Dwgs.User" user "User.Drawings")
		(19 "Cmts.User" user "User.Comments")
		(21 "Eco1.User" user "User.Eco1")
		(23 "Eco2.User" user "User.Eco2")
		(25 "Edge.Cuts" user "Board Geometry/Outline")
		(27 "Margin" user)
		(31 "F.CrtYd" user "Package Geometry/Place Bound Top")
		(29 "B.CrtYd" user "Package Geometry/Place Bound Bottom")
		(35 "F.Fab" user "Ref Des/Assembly Top")
		(33 "B.Fab" user "Ref Des/Assembly Bottom")
	)
	(footprint ""
		(layer "B.Cu")
		(at 203.33208 -36.642548 180)
		(property "Reference" "R3578"
			(at 0 0 0)
			(layer "B.SilkS")
			(hide yes)
			(effects
				(font
					(size 1.27 1.27)
				)
				(justify mirror)
			)
		)
		(property "Value" ""
			(at 0 0 0)
			(layer "B.Fab")
			(effects
				(font
					(size 1.27 1.27)
				)
				(justify mirror)
			)
		)
		(duplicate_pad_numbers_are_jumpers no)
		(fp_line
			(start 0.7874 0.4064)
			(end 0.7874 -0.4064)
			(stroke
				(width 0.1524)
				(type default)
			)
			(layer "B.SilkS")
		)
		(fp_line
			(start 0.7874 -0.4064)
			(end -0.7874 -0.4064)
			(stroke
				(width 0.1524)
				(type default)
			)
			(layer "B.SilkS")
		)
		(fp_line
			(start -0.7874 0.4064)
			(end 0.7874 0.4064)
			(stroke
				(width 0.1524)
				(type default)
			)
			(layer "B.SilkS")
		)
		(fp_line
			(start -0.7874 -0.4064)
			(end -0.7874 0.4064)
			(stroke
				(width 0.1524)
				(type default)
			)
			(layer "B.SilkS")
		)
		(fp_line
			(start 0.67945 0.3048)
			(end 0.67945 -0.305054)
			(stroke
				(width 0.1)
				(type default)
			)
			(layer "B.Fab")
		)
		(fp_line
			(start 0.67945 -0.305054)
			(end 0.12065 -0.305054)
			(stroke
				(width 0.1)
				(type default)
			)
			(layer "B.Fab")
		)
		(fp_line
			(start 0.12065 0.3048)
			(end 0.67945 0.3048)
			(stroke
				(width 0.1)
				(type default)
			)
			(layer "B.Fab")
		)
		(fp_line
			(start 0.12065 0.2794)
			(end 0.12065 0.3048)
			(stroke
				(width 0.1)
				(type default)
			)
			(layer "B.Fab")
		)
		(fp_line
			(start 0.12065 -0.2794)
			(end -0.12065 -0.2794)
			(stroke
				(width 0.1)
				(type default)
			)
			(layer "B.Fab")
		)
		(fp_line
			(start 0.12065 -0.305054)
			(end 0.12065 -0.2794)
			(stroke
				(width 0.1)
				(type default)
			)
			(layer "B.Fab")
		)
		(fp_line
			(start -0.120396 0.3048)
			(end -0.120396 0.2794)
			(stroke
				(width 0.1)
				(type default)
			)
			(layer "B.Fab")
		)
		(fp_line
			(start -0.120396 0.2794)
			(end 0.12065 0.2794)
			(stroke
				(width 0.1)
				(type default)
			)
			(layer "B.Fab")
		)
		(fp_line
			(start -0.12065 -0.2794)
			(end -0.12065 -0.3048)
			(stroke
				(width 0.1)
				(type default)
			)
			(layer "B.Fab")
		)
		(fp_line
			(start -0.12065 -0.3048)
			(end -0.67945 -0.3048)
			(stroke
				(width 0.1)
				(type default)
			)
			(layer "B.Fab")
		)
		(fp_line
			(start -0.67945 0.3048)
			(end -0.120396 0.3048)
			(stroke
				(width 0.1)
				(type default)
			)
			(layer "B.Fab")
		)
		(fp_line
			(start -0.67945 -0.3048)
			(end -0.67945 0.3048)
			(stroke
				(width 0.1)
				(type default)
			)
			(layer "B.Fab")
		)
		(pad "1" smd circle
			(at 0.40005 0)
			(size 0 0)
			(layers "B.Cu" "B.Mask" "B.Paste")
			(net "P12V_SCM_R")
		)
		(pad "2" smd circle
			(at -0.40005 0)
			(size 0 0)
			(layers "B.Cu" "B.Mask" "B.Paste")
			(net "VSENSE_P12V_INA230_5_INP")
		)
	)
	(footprint ""
		(layer "B.Cu")
		(at 109.45114 -356.507288 -90)
		(property "Reference" "PR4239"
			(at 0 0 90)
			(layer "B.SilkS")
			(hide yes)
			(effects
				(font
					(size 1.27 1.27)
				)
				(justify mirror)
			)
		)
		(property "Value" ""
			(at 0 0 90)
			(layer "B.Fab")
			(effects
				(font
					(size 1.27 1.27)
				)
				(justify mirror)
			)
		)
		(duplicate_pad_numbers_are_jumpers no)
		(fp_line
			(start -0.7874 0.4064)
			(end 0.7874 0.4064)
			(stroke
				(width 0.1524)
				(type default)
			)
			(layer "B.SilkS")
		)
		(fp_line
			(start 0.7874 0.4064)
			(end 0.7874 -0.4064)
			(stroke
				(width 0.1524)
				(type default)
			)
			(layer "B.SilkS")
		)
		(fp_line
			(start -0.7874 -0.4064)
			(end -0.7874 0.4064)
			(stroke
				(width 0.1524)
				(type default)
			)
			(layer "B.SilkS")
		)
		(fp_line
			(start 0.7874 -0.4064)
			(end -0.7874 -0.4064)
			(stroke
				(width 0.1524)
				(type default)
			)
			(layer "B.SilkS")
		)
		(fp_line
			(start -0.67945 0.3048)
			(end -0.120396 0.3048)
			(stroke
				(width 0.1)
				(type default)
			)
			(layer "B.Fab")
		)
		(fp_line
			(start -0.120396 0.3048)
			(end -0.120396 0.2794)
			(stroke
				(width 0.1)
				(type default)
			)
			(layer "B.Fab")
		)
		(fp_line
			(start 0.12065 0.3048)
			(end 0.67945 0.3048)
			(stroke
				(width 0.1)
				(type default)
			)
			(layer "B.Fab")
		)
		(fp_line
			(start 0.67945 0.3048)
			(end 0.67945 -0.305054)
			(stroke
				(width 0.1)
				(type default)
			)
			(layer "B.Fab")
		)
		(fp_line
			(start -0.120396 0.2794)
			(end 0.12065 0.2794)
			(stroke
				(width 0.1)
				(type default)
			)
			(layer "B.Fab")
		)
		(fp_line
			(start 0.12065 0.2794)
			(end 0.12065 0.3048)
			(stroke
				(width 0.1)
				(type default)
			)
			(layer "B.Fab")
		)
		(fp_line
			(start -0.12065 -0.2794)
			(end -0.12065 -0.3048)
			(stroke
				(width 0.1)
				(type default)
			)
			(layer "B.Fab")
		)
		(fp_line
			(start 0.12065 -0.2794)
			(end -0.12065 -0.2794)
			(stroke
				(width 0.1)
				(type default)
			)
			(layer "B.Fab")
		)
		(fp_line
			(start -0.67945 -0.3048)
			(end -0.67945 0.3048)
			(stroke
				(width 0.1)
				(type default)
			)
			(layer "B.Fab")
		)
		(fp_line
			(start -0.12065 -0.3048)
			(end -0.67945 -0.3048)
			(stroke
				(width 0.1)
				(type default)
			)
			(layer "B.Fab")
		)
		(fp_line
			(start 0.12065 -0.305054)
			(end 0.12065 -0.2794)
			(stroke
				(width 0.1)
				(type default)
			)
			(layer "B.Fab")
		)
		(fp_line
			(start 0.67945 -0.305054)
			(end 0.12065 -0.305054)
			(stroke
				(width 0.1)
				(type default)
			)
			(layer "B.Fab")
		)
		(pad "1" smd circle
			(at 0.40005 0 90)
			(size 0 0)
			(layers "B.Cu" "B.Mask" "B.Paste")
			(net "PVCCFA_EHV_FIVRA_CPU1_IMON3")
		)
		(pad "2" smd circle
			(at -0.40005 0 90)
			(size 0 0)
			(layers "B.Cu" "B.Mask" "B.Paste")
			(net "GND")
		)
	)
)
